(kicad_pcb
	(version 20260206)
	(generator "pcbnew")
	(generator_version "10.0")
	(general
		(thickness 1.6)
		(legacy_teardrops no)
	)
	(paper "A4")
	(title_block
		(title "v2-tray-backplane — ms_tbp_v2.brd")
		(comment 1 "Open CloudServer (Microsoft) / footprint 158 of 164 (J1), pads 1-95 of 155")
	)
	(layers
		(0 "F.Cu" signal "TOP")
		(4 "In1.Cu" signal "LYR2")
		(6 "In2.Cu" signal "LYR3")
		(8 "In3.Cu" signal "LYR4")
		(10 "In4.Cu" signal "LYR5")
		(12 "In5.Cu" signal "LYR6")
		(14 "In6.Cu" signal "LYR7")
		(2 "B.Cu" signal "BOTTOM")
		(9 "F.Adhes" user "F.Adhesive")
		(11 "B.Adhes" user "B.Adhesive")
		(13 "F.Paste" user "Package Geometry/Pastemask Top")
		(15 "B.Paste" user "Package Geometry/Pastemask Bottom")
		(5 "F.SilkS" user "Ref Des/Silkscreen Top")
		(7 "B.SilkS" user "Ref Des/Silkscreen Bottom")
		(1 "F.Mask" user "Board Geometry/Soldermask Top")
		(3 "B.Mask" user "Board Geometry/Soldermask Bottom")
		(17 "Dwgs.User" user "User.Drawings")
		(19 "Cmts.User" user "User.Comments")
		(21 "Eco1.User" user "User.Eco1")
		(23 "Eco2.User" user "User.Eco2")
		(25 "Edge.Cuts" user "Board Geometry/Outline")
		(27 "Margin" user)
		(31 "F.CrtYd" user "Package Geometry/Place Bound Top")
		(29 "B.CrtYd" user "Package Geometry/Place Bound Bottom")
		(35 "F.Fab" user "Ref Des/Assembly Top")
		(33 "B.Fab" user "Ref Des/Assembly Bottom")
	)
	(footprint ""
		(layer "F.Cu")
		(at -392.46 45.260001 180)
		(property "Reference" "J1"
			(at 9 24.584899 0)
			(unlocked yes)
			(layer "F.SilkS")
			(effects
				(font
					(size 0.762 0.5334)
					(thickness 0.1016)
				)
			)
		)
		(property "Value" ""
			(at 0 0 180)
			(layer "F.Fab")
			(effects
				(font
					(size 1.27 1.27)
				)
			)
		)
		(duplicate_pad_numbers_are_jumpers no)
		(pad "A1" thru_hole rect
			(at 0 0 180)
			(size 0.8128 0.8128)
			(drill 0.508)
			(layers "*.Cu" "*.Mask")
			(remove_unused_layers no)
			(net "PCIE_T2B_B1_RX_DP<7>")
			(padstack
				(mode front_inner_back)
				(layer "Inner"
					(shape circle)
					(size 0.8128 0.8128)
				)
				(layer "B.Cu"
					(shape rect)
					(size 0.8128 0.8128)
				)
			)
		)
		(pad "A2" thru_hole circle
			(at 2.000001 -0.1 180)
			(size 0.8128 0.8128)
			(drill 0.508)
			(layers "*.Cu" "*.Mask")
			(remove_unused_layers no)
			(net "GND")
		)
		(pad "A3" thru_hole circle
			(at 4 0 180)
			(size 0.8128 0.8128)
			(drill 0.508)
			(layers "*.Cu" "*.Mask")
			(remove_unused_layers no)
			(net "PCIE_T2B_B1_RX_DP<5>")
		)
		(pad "A4" thru_hole circle
			(at 6.000001 -0.1 180)
			(size 0.8128 0.8128)
			(drill 0.508)
			(layers "*.Cu" "*.Mask")
			(remove_unused_layers no)
			(net "GND")
		)
		(pad "A5" thru_hole circle
			(at 7.999999 0 180)
			(size 0.8128 0.8128)
			(drill 0.508)
			(layers "*.Cu" "*.Mask")
			(remove_unused_layers no)
			(net "PCIE_T2B_B1_RX_DP<3>")
		)
		(pad "A6" thru_hole circle
			(at 10 -0.1 180)
			(size 0.8128 0.8128)
			(drill 0.508)
			(layers "*.Cu" "*.Mask")
			(remove_unused_layers no)
			(net "GND")
		)
		(pad "A7" thru_hole circle
			(at 11.999999 0 180)
			(size 0.8128 0.8128)
			(drill 0.508)
			(layers "*.Cu" "*.Mask")
			(remove_unused_layers no)
			(net "PCIE_T2B_B1_RX_DP<1>")
		)
		(pad "A8" thru_hole circle
			(at 14 -0.1 180)
			(size 0.8128 0.8128)
			(drill 0.508)
			(layers "*.Cu" "*.Mask")
			(remove_unused_layers no)
			(net "GND")
		)
		(pad "A9" thru_hole circle
			(at 16.000001 0 180)
			(size 0.8128 0.8128)
			(drill 0.508)
			(layers "*.Cu" "*.Mask")
			(remove_unused_layers no)
			(net "CLK_100M_B1_P<0>")
		)
		(pad "A10" thru_hole circle
			(at 18 -0.1 180)
			(size 0.8128 0.8128)
			(drill 0.508)
			(layers "*.Cu" "*.Mask")
			(remove_unused_layers no)
			(net "GND")
		)
		(pad "B1" thru_hole circle
			(at 0 1.4 180)
			(size 0.8128 0.8128)
			(drill 0.508)
			(layers "*.Cu" "*.Mask")
			(remove_unused_layers no)
			(net "PCIE_T2B_B1_RX_DN<7>")
		)
		(pad "B2" thru_hole circle
			(at 2.000001 1.3 180)
			(size 0.8128 0.8128)
			(drill 0.508)
			(layers "*.Cu" "*.Mask")
			(remove_unused_layers no)
			(net "PCIE_T2B_B1_RX_DP<6>")
		)
		(pad "B3" thru_hole circle
			(at 4 1.4 180)
			(size 0.8128 0.8128)
			(drill 0.508)
			(layers "*.Cu" "*.Mask")
			(remove_unused_layers no)
			(net "PCIE_T2B_B1_RX_DN<5>")
		)
		(pad "B4" thru_hole circle
			(at 6.000001 1.3 180)
			(size 0.8128 0.8128)
			(drill 0.508)
			(layers "*.Cu" "*.Mask")
			(remove_unused_layers no)
			(net "PCIE_T2B_B1_RX_DP<4>")
		)
		(pad "B5" thru_hole circle
			(at 7.999999 1.4 180)
			(size 0.8128 0.8128)
			(drill 0.508)
			(layers "*.Cu" "*.Mask")
			(remove_unused_layers no)
			(net "PCIE_T2B_B1_RX_DN<3>")
		)
		(pad "B6" thru_hole circle
			(at 10 1.3 180)
			(size 0.8128 0.8128)
			(drill 0.508)
			(layers "*.Cu" "*.Mask")
			(remove_unused_layers no)
			(net "PCIE_T2B_B1_RX_DP<2>")
		)
		(pad "B7" thru_hole circle
			(at 11.999999 1.4 180)
			(size 0.8128 0.8128)
			(drill 0.508)
			(layers "*.Cu" "*.Mask")
			(remove_unused_layers no)
			(net "PCIE_T2B_B1_RX_DN<1>")
		)
		(pad "B8" thru_hole circle
			(at 14 1.3 180)
			(size 0.8128 0.8128)
			(drill 0.508)
			(layers "*.Cu" "*.Mask")
			(remove_unused_layers no)
			(net "PCIE_T2B_B1_RX_DP<0>")
		)
		(pad "B9" thru_hole circle
			(at 16.000001 1.4 180)
			(size 0.8128 0.8128)
			(drill 0.508)
			(layers "*.Cu" "*.Mask")
			(remove_unused_layers no)
			(net "CLK_100M_B1_N<0>")
		)
		(pad "B10" thru_hole circle
			(at 18 1.3 180)
			(size 0.8128 0.8128)
			(drill 0.508)
			(layers "*.Cu" "*.Mask")
			(remove_unused_layers no)
			(net "USB_B1_P")
		)
		(pad "C1" thru_hole circle
			(at 0 2.799999 180)
			(size 0.8128 0.8128)
			(drill 0.508)
			(layers "*.Cu" "*.Mask")
			(remove_unused_layers no)
			(net "GND")
		)
		(pad "C2" thru_hole circle
			(at 2.000001 2.7 180)
			(size 0.8128 0.8128)
			(drill 0.508)
			(layers "*.Cu" "*.Mask")
			(remove_unused_layers no)
			(net "PCIE_T2B_B1_RX_DN<6>")
		)
		(pad "C3" thru_hole circle
			(at 4 2.799999 180)
			(size 0.8128 0.8128)
			(drill 0.508)
			(layers "*.Cu" "*.Mask")
			(remove_unused_layers no)
			(net "GND")
		)
		(pad "C4" thru_hole circle
			(at 6.000001 2.7 180)
			(size 0.8128 0.8128)
			(drill 0.508)
			(layers "*.Cu" "*.Mask")
			(remove_unused_layers no)
			(net "PCIE_T2B_B1_RX_DN<4>")
		)
		(pad "C5" thru_hole circle
			(at 7.999999 2.799999 180)
			(size 0.8128 0.8128)
			(drill 0.508)
			(layers "*.Cu" "*.Mask")
			(remove_unused_layers no)
			(net "GND")
		)
		(pad "C6" thru_hole circle
			(at 10 2.7 180)
			(size 0.8128 0.8128)
			(drill 0.508)
			(layers "*.Cu" "*.Mask")
			(remove_unused_layers no)
			(net "PCIE_T2B_B1_RX_DN<2>")
		)
		(pad "C7" thru_hole circle
			(at 11.999999 2.799999 180)
			(size 0.8128 0.8128)
			(drill 0.508)
			(layers "*.Cu" "*.Mask")
			(remove_unused_layers no)
			(net "GND")
		)
		(pad "C8" thru_hole circle
			(at 14 2.7 180)
			(size 0.8128 0.8128)
			(drill 0.508)
			(layers "*.Cu" "*.Mask")
			(remove_unused_layers no)
			(net "PCIE_T2B_B1_RX_DN<0>")
		)
		(pad "C9" thru_hole circle
			(at 16.000001 2.799999 180)
			(size 0.8128 0.8128)
			(drill 0.508)
			(layers "*.Cu" "*.Mask")
			(remove_unused_layers no)
			(net "GND")
		)
		(pad "C10" thru_hole circle
			(at 18 2.7 180)
			(size 0.8128 0.8128)
			(drill 0.508)
			(layers "*.Cu" "*.Mask")
			(remove_unused_layers no)
			(net "USB_B1_N")
		)
		(pad "D1" thru_hole circle
			(at 0 4.199999 180)
			(size 0.8128 0.8128)
			(drill 0.508)
			(layers "*.Cu" "*.Mask")
			(remove_unused_layers no)
			(net "PCIE_T2B_B1_RX_DP<15>")
		)
		(pad "D2" thru_hole circle
			(at 2.000001 4.099999 180)
			(size 0.8128 0.8128)
			(drill 0.508)
			(layers "*.Cu" "*.Mask")
			(remove_unused_layers no)
			(net "GND")
		)
		(pad "D3" thru_hole circle
			(at 4 4.199999 180)
			(size 0.8128 0.8128)
			(drill 0.508)
			(layers "*.Cu" "*.Mask")
			(remove_unused_layers no)
			(net "PCIE_T2B_B1_RX_DP<13>")
		)
		(pad "D4" thru_hole circle
			(at 6.000001 4.099999 180)
			(size 0.8128 0.8128)
			(drill 0.508)
			(layers "*.Cu" "*.Mask")
			(remove_unused_layers no)
			(net "GND")
		)
		(pad "D5" thru_hole circle
			(at 7.999999 4.199999 180)
			(size 0.8128 0.8128)
			(drill 0.508)
			(layers "*.Cu" "*.Mask")
			(remove_unused_layers no)
			(net "PCIE_T2B_B1_RX_DP<11>")
		)
		(pad "D6" thru_hole circle
			(at 10 4.099999 180)
			(size 0.8128 0.8128)
			(drill 0.508)
			(layers "*.Cu" "*.Mask")
			(remove_unused_layers no)
			(net "GND")
		)
		(pad "D7" thru_hole circle
			(at 11.999999 4.199999 180)
			(size 0.8128 0.8128)
			(drill 0.508)
			(layers "*.Cu" "*.Mask")
			(remove_unused_layers no)
			(net "PCIE_T2B_B1_RX_DP<9>")
		)
		(pad "D8" thru_hole circle
			(at 14 4.099999 180)
			(size 0.8128 0.8128)
			(drill 0.508)
			(layers "*.Cu" "*.Mask")
			(remove_unused_layers no)
			(net "GND")
		)
		(pad "D9" thru_hole circle
			(at 16.000001 4.199999 180)
			(size 0.8128 0.8128)
			(drill 0.508)
			(layers "*.Cu" "*.Mask")
			(remove_unused_layers no)
			(net "CLK_100M_B1_P<1>")
		)
		(pad "D10" thru_hole circle
			(at 18 4.099999 180)
			(size 0.8128 0.8128)
			(drill 0.508)
			(layers "*.Cu" "*.Mask")
			(remove_unused_layers no)
			(net "GND")
		)
		(pad "E1" thru_hole circle
			(at 0 5.599999 180)
			(size 0.8128 0.8128)
			(drill 0.508)
			(layers "*.Cu" "*.Mask")
			(remove_unused_layers no)
			(net "PCIE_T2B_B1_RX_DN<15>")
		)
		(pad "E2" thru_hole circle
			(at 2.000001 5.499999 180)
			(size 0.8128 0.8128)
			(drill 0.508)
			(layers "*.Cu" "*.Mask")
			(remove_unused_layers no)
			(net "PCIE_T2B_B1_RX_DP<14>")
		)
		(pad "E3" thru_hole circle
			(at 4 5.599999 180)
			(size 0.8128 0.8128)
			(drill 0.508)
			(layers "*.Cu" "*.Mask")
			(remove_unused_layers no)
			(net "PCIE_T2B_B1_RX_DN<13>")
		)
		(pad "E4" thru_hole circle
			(at 6.000001 5.499999 180)
			(size 0.8128 0.8128)
			(drill 0.508)
			(layers "*.Cu" "*.Mask")
			(remove_unused_layers no)
			(net "PCIE_T2B_B1_RX_DP<12>")
		)
		(pad "E5" thru_hole circle
			(at 7.999999 5.599999 180)
			(size 0.8128 0.8128)
			(drill 0.508)
			(layers "*.Cu" "*.Mask")
			(remove_unused_layers no)
			(net "PCIE_T2B_B1_RX_DN<11>")
		)
		(pad "E6" thru_hole circle
			(at 10 5.499999 180)
			(size 0.8128 0.8128)
			(drill 0.508)
			(layers "*.Cu" "*.Mask")
			(remove_unused_layers no)
			(net "PCIE_T2B_B1_RX_DP<10>")
		)
		(pad "E7" thru_hole circle
			(at 11.999999 5.599999 180)
			(size 0.8128 0.8128)
			(drill 0.508)
			(layers "*.Cu" "*.Mask")
			(remove_unused_layers no)
			(net "PCIE_T2B_B1_RX_DN<9>")
		)
		(pad "E8" thru_hole circle
			(at 14 5.499999 180)
			(size 0.8128 0.8128)
			(drill 0.508)
			(layers "*.Cu" "*.Mask")
			(remove_unused_layers no)
			(net "PCIE_T2B_B1_RX_DP<8>")
		)
		(pad "E9" thru_hole circle
			(at 16.000001 5.599999 180)
			(size 0.8128 0.8128)
			(drill 0.508)
			(layers "*.Cu" "*.Mask")
			(remove_unused_layers no)
			(net "CLK_100M_B1_N<1>")
		)
		(pad "E10" thru_hole circle
			(at 18 5.499999 180)
			(size 0.8128 0.8128)
			(drill 0.508)
			(layers "*.Cu" "*.Mask")
			(remove_unused_layers no)
			(net "P5V_USB_B1")
		)
		(pad "F1" thru_hole circle
			(at 0 7.000001 180)
			(size 0.8128 0.8128)
			(drill 0.508)
			(layers "*.Cu" "*.Mask")
			(remove_unused_layers no)
			(net "GND")
		)
		(pad "F2" thru_hole circle
			(at 2.000001 6.899999 180)
			(size 0.8128 0.8128)
			(drill 0.508)
			(layers "*.Cu" "*.Mask")
			(remove_unused_layers no)
			(net "PCIE_T2B_B1_RX_DN<14>")
		)
		(pad "F3" thru_hole circle
			(at 4 7.000001 180)
			(size 0.8128 0.8128)
			(drill 0.508)
			(layers "*.Cu" "*.Mask")
			(remove_unused_layers no)
			(net "GND")
		)
		(pad "F4" thru_hole circle
			(at 6.000001 6.899999 180)
			(size 0.8128 0.8128)
			(drill 0.508)
			(layers "*.Cu" "*.Mask")
			(remove_unused_layers no)
			(net "PCIE_T2B_B1_RX_DN<12>")
		)
		(pad "F5" thru_hole circle
			(at 7.999999 7.000001 180)
			(size 0.8128 0.8128)
			(drill 0.508)
			(layers "*.Cu" "*.Mask")
			(remove_unused_layers no)
			(net "GND")
		)
		(pad "F6" thru_hole circle
			(at 10 6.899999 180)
			(size 0.8128 0.8128)
			(drill 0.508)
			(layers "*.Cu" "*.Mask")
			(remove_unused_layers no)
			(net "PCIE_T2B_B1_RX_DN<10>")
		)
		(pad "F7" thru_hole circle
			(at 11.999999 7.000001 180)
			(size 0.8128 0.8128)
			(drill 0.508)
			(layers "*.Cu" "*.Mask")
			(remove_unused_layers no)
			(net "GND")
		)
		(pad "F8" thru_hole circle
			(at 14 6.899999 180)
			(size 0.8128 0.8128)
			(drill 0.508)
			(layers "*.Cu" "*.Mask")
			(remove_unused_layers no)
			(net "PCIE_T2B_B1_RX_DN<8>")
		)
		(pad "F9" thru_hole circle
			(at 16.000001 7.000001 180)
			(size 0.8128 0.8128)
			(drill 0.508)
			(layers "*.Cu" "*.Mask")
			(remove_unused_layers no)
			(net "GND")
		)
		(pad "F10" thru_hole circle
			(at 18 6.899999 180)
			(size 0.8128 0.8128)
			(drill 0.508)
			(layers "*.Cu" "*.Mask")
			(remove_unused_layers no)
			(net "GND")
		)
		(pad "G1" thru_hole circle
			(at 0 8.400001 180)
			(size 0.8128 0.8128)
			(drill 0.508)
			(layers "*.Cu" "*.Mask")
			(remove_unused_layers no)
			(net "PCIE_RESET_B1_N<3>")
		)
		(pad "G2" thru_hole circle
			(at 2.000001 8.300001 180)
			(size 0.8128 0.8128)
			(drill 0.508)
			(layers "*.Cu" "*.Mask")
			(remove_unused_layers no)
			(net "GND")
		)
		(pad "G3" thru_hole circle
			(at 4 8.400001 180)
			(size 0.8128 0.8128)
			(drill 0.508)
			(layers "*.Cu" "*.Mask")
			(remove_unused_layers no)
			(net "PCIE_CFG_B1_ID0")
		)
		(pad "G4" thru_hole circle
			(at 6.000001 8.300001 180)
			(size 0.8128 0.8128)
			(drill 0.508)
			(layers "*.Cu" "*.Mask")
			(remove_unused_layers no)
			(net "GND")
		)
		(pad "G5" thru_hole circle
			(at 7.999999 8.400001 180)
			(size 0.8128 0.8128)
			(drill 0.508)
			(layers "*.Cu" "*.Mask")
			(remove_unused_layers no)
			(net "MEZZ_B1_SCL")
		)
		(pad "G6" thru_hole circle
			(at 10 8.300001 180)
			(size 0.8128 0.8128)
			(drill 0.508)
			(layers "*.Cu" "*.Mask")
			(remove_unused_layers no)
			(net "GND")
		)
		(pad "G7" thru_hole circle
			(at 11.999999 8.400001 180)
			(size 0.8128 0.8128)
			(drill 0.508)
			(layers "*.Cu" "*.Mask")
			(remove_unused_layers no)
			(net "Net_3")
		)
		(pad "G8" thru_hole circle
			(at 14 8.300001 180)
			(size 0.8128 0.8128)
			(drill 0.508)
			(layers "*.Cu" "*.Mask")
			(remove_unused_layers no)
			(net "GND")
		)
		(pad "G9" thru_hole circle
			(at 16.000001 8.400001 180)
			(size 0.8128 0.8128)
			(drill 0.508)
			(layers "*.Cu" "*.Mask")
			(remove_unused_layers no)
			(net "CLK_100M_B1_P<2>")
		)
		(pad "G10" thru_hole circle
			(at 18 8.300001 180)
			(size 0.8128 0.8128)
			(drill 0.508)
			(layers "*.Cu" "*.Mask")
			(remove_unused_layers no)
			(net "GND")
		)
		(pad "H1" thru_hole circle
			(at 0 9.800001 180)
			(size 0.8128 0.8128)
			(drill 0.508)
			(layers "*.Cu" "*.Mask")
			(remove_unused_layers no)
			(net "PCIE_RESET_B1_N<2>")
		)
		(pad "H2" thru_hole circle
			(at 2.000001 9.700001 180)
			(size 0.8128 0.8128)
			(drill 0.508)
			(layers "*.Cu" "*.Mask")
			(remove_unused_layers no)
			(net "PCIE_RESET_B1_N<1>")
		)
		(pad "H3" thru_hole circle
			(at 4 9.800001 180)
			(size 0.8128 0.8128)
			(drill 0.508)
			(layers "*.Cu" "*.Mask")
			(remove_unused_layers no)
			(net "PCIE_CFG_B1_ID1")
		)
		(pad "H4" thru_hole circle
			(at 6.000001 9.700001 180)
			(size 0.8128 0.8128)
			(drill 0.508)
			(layers "*.Cu" "*.Mask")
			(remove_unused_layers no)
			(net "PCIE_WAKE_B1_N")
		)
		(pad "H5" thru_hole circle
			(at 7.999999 9.800001 180)
			(size 0.8128 0.8128)
			(drill 0.508)
			(layers "*.Cu" "*.Mask")
			(remove_unused_layers no)
			(net "MEZZ_B1_EN")
		)
		(pad "H6" thru_hole circle
			(at 10 9.700001 180)
			(size 0.8128 0.8128)
			(drill 0.508)
			(layers "*.Cu" "*.Mask")
			(remove_unused_layers no)
			(net "MEZZ_PRESENT_B1_N")
		)
		(pad "H7" thru_hole circle
			(at 11.999999 9.800001 180)
			(size 0.8128 0.8128)
			(drill 0.508)
			(layers "*.Cu" "*.Mask")
			(remove_unused_layers no)
			(net "PSU_B1_ALERT_N")
		)
		(pad "H8" thru_hole circle
			(at 14 9.700001 180)
			(size 0.8128 0.8128)
			(drill 0.508)
			(layers "*.Cu" "*.Mask")
			(remove_unused_layers no)
			(net "SERIAL_B1_TX2")
		)
		(pad "H9" thru_hole circle
			(at 16.000001 9.800001 180)
			(size 0.8128 0.8128)
			(drill 0.508)
			(layers "*.Cu" "*.Mask")
			(remove_unused_layers no)
			(net "CLK_100M_B1_N<2>")
		)
		(pad "H10" thru_hole circle
			(at 18 9.700001 180)
			(size 0.8128 0.8128)
			(drill 0.508)
			(layers "*.Cu" "*.Mask")
			(remove_unused_layers no)
			(net "GND")
		)
		(pad "I1" thru_hole circle
			(at 0 11.2 180)
			(size 0.8128 0.8128)
			(drill 0.508)
			(layers "*.Cu" "*.Mask")
			(remove_unused_layers no)
			(net "GND")
		)
		(pad "I2" thru_hole circle
			(at 2.000001 11.100001 180)
			(size 0.8128 0.8128)
			(drill 0.508)
			(layers "*.Cu" "*.Mask")
			(remove_unused_layers no)
			(net "PCIE_RESET_B1_N<0>")
		)
		(pad "I3" thru_hole circle
			(at 4 11.2 180)
			(size 0.8128 0.8128)
			(drill 0.508)
			(layers "*.Cu" "*.Mask")
			(remove_unused_layers no)
			(net "GND")
		)
		(pad "I4" thru_hole circle
			(at 6.000001 11.100001 180)
			(size 0.8128 0.8128)
			(drill 0.508)
			(layers "*.Cu" "*.Mask")
			(remove_unused_layers no)
			(net "MEZZ_B1_SDA")
		)
		(pad "I5" thru_hole circle
			(at 7.999999 11.2 180)
			(size 0.8128 0.8128)
			(drill 0.508)
			(layers "*.Cu" "*.Mask")
			(remove_unused_layers no)
			(net "GND")
		)
		(pad "I6" thru_hole circle
			(at 10 11.100001 180)
			(size 0.8128 0.8128)
			(drill 0.508)
			(layers "*.Cu" "*.Mask")
			(remove_unused_layers no)
			(net "BLADE_MATED_B1_N<0>")
		)
		(pad "I7" thru_hole circle
			(at 11.999999 11.2 180)
			(size 0.8128 0.8128)
			(drill 0.508)
			(layers "*.Cu" "*.Mask")
			(remove_unused_layers no)
			(net "GND")
		)
		(pad "I8" thru_hole circle
			(at 14 11.100001 180)
			(size 0.8128 0.8128)
			(drill 0.508)
			(layers "*.Cu" "*.Mask")
			(remove_unused_layers no)
			(net "SERIAL_B1_RX2")
		)
		(pad "I9" thru_hole circle
			(at 16.000001 11.2 180)
			(size 0.8128 0.8128)
			(drill 0.508)
			(layers "*.Cu" "*.Mask")
			(remove_unused_layers no)
			(net "GND")
		)
		(pad "I10" thru_hole circle
			(at 18 11.100001 180)
			(size 0.8128 0.8128)
			(drill 0.508)
			(layers "*.Cu" "*.Mask")
			(remove_unused_layers no)
			(net "P12V_MEZZ_B1")
		)
		(pad "J1" thru_hole circle
			(at 0 12.6 180)
			(size 0.8128 0.8128)
			(drill 0.508)
			(layers "*.Cu" "*.Mask")
			(remove_unused_layers no)
			(net "PCIE_B2T_B1_TX_DP<7>")
		)
		(pad "J2" thru_hole circle
			(at 2.000001 12.5 180)
			(size 0.8128 0.8128)
			(drill 0.508)
			(layers "*.Cu" "*.Mask")
			(remove_unused_layers no)
			(net "GND")
		)
		(pad "J3" thru_hole circle
			(at 4 12.6 180)
			(size 0.8128 0.8128)
			(drill 0.508)
			(layers "*.Cu" "*.Mask")
			(remove_unused_layers no)
			(net "PCIE_B2T_B1_TX_DP<5>")
		)
		(pad "J4" thru_hole circle
			(at 6.000001 12.5 180)
			(size 0.8128 0.8128)
			(drill 0.508)
			(layers "*.Cu" "*.Mask")
			(remove_unused_layers no)
			(net "GND")
		)
		(pad "J5" thru_hole circle
			(at 7.999999 12.6 180)
			(size 0.8128 0.8128)
			(drill 0.508)
			(layers "*.Cu" "*.Mask")
			(remove_unused_layers no)
			(net "PCIE_B2T_B1_TX_DP<3>")
		)
	)
)
